(kicad_pcb
	(version 20241229)
	(generator "pcbnew")
	(generator_version "9.0")
	(general
		(thickness 1.599998)
		(legacy_teardrops no)
	)
	(paper "A4")
	(title_block
		(date "2023-02-12")
		(rev "1.1.5")
		(comment 9 "footprints 287-289 of 473")
	)
	(layers
		(0 "F.Cu" signal)
		(4 "In1.Cu" power "In1.GND")
		(6 "In2.Cu" signal)
		(8 "In3.Cu" power "In3.GND")
		(10 "In4.Cu" power "In4.VCC")
		(12 "In5.Cu" signal)
		(14 "In6.Cu" power "In6.VCC")
		(2 "B.Cu" signal)
		(9 "F.Adhes" user "F.Adhesive")
		(11 "B.Adhes" user "B.Adhesive")
		(13 "F.Paste" user)
		(15 "B.Paste" user)
		(5 "F.SilkS" user "F.Silkscreen")
		(7 "B.SilkS" user "B.Silkscreen")
		(1 "F.Mask" user)
		(3 "B.Mask" user)
		(17 "Dwgs.User" user "User.Drawings")
		(19 "Cmts.User" user "User.Comments")
		(21 "Eco1.User" user "User.Eco1")
		(23 "Eco2.User" user "User.Eco2")
		(25 "Edge.Cuts" user)
		(27 "Margin" user)
		(31 "F.CrtYd" user "F.Courtyard")
		(29 "B.CrtYd" user "B.Courtyard")
		(35 "F.Fab" user)
		(33 "B.Fab" user)
	)
	(footprint "antmicro-footprints:TP_SMD_1mm"
		(layer "F.Cu")
		(at 144.7 87.599)
		(property "Reference" "TP16"
			(at -1.4 -5.861996 0)
			(layer "F.SilkS")
			(effects
				(font
					(size 0.7 0.7)
					(thickness 0.15)
				)
				(justify left bottom)
			)
		)
		(property "Value" "TP_1mm_SMD"
			(at 0 1.4 0)
			(layer "F.Fab")
			(effects
				(font
					(size 0.7 0.7)
					(thickness 0.15)
				)
				(justify left bottom)
			)
		)
		(property "Description" "Test Point 1mm"
			(at 0 0 0)
			(layer "F.Fab")
			(hide yes)
			(effects
				(font
					(size 1.27 1.27)
					(thickness 0.15)
				)
			)
		)
		(property "Author" "Antmicro"
			(at 0 0 0)
			(layer "F.Fab")
			(hide yes)
			(effects
				(font
					(size 1 1)
					(thickness 0.15)
				)
			)
		)
		(property "License" "Apache-2.0"
			(at 0 0 0)
			(layer "F.Fab")
			(hide yes)
			(effects
				(font
					(size 1 1)
					(thickness 0.15)
				)
			)
		)
		(property "MPN" ""
			(at 0 0 0)
			(layer "F.Fab")
			(hide yes)
			(effects
				(font
					(size 1 1)
					(thickness 0.15)
				)
			)
		)
		(property "Manufacturer" ""
			(at 0 0 0)
			(layer "F.Fab")
			(hide yes)
			(effects
				(font
					(size 1 1)
					(thickness 0.15)
				)
			)
		)
		(sheetname "Supply")
		(sheetfile "supply.kicad_sch")
		(attr exclude_from_pos_files)
		(pad "1" smd circle
			(at 0 0)
			(size 1 1)
			(layers "F.Cu" "F.Mask")
			(net 461 "1V1_SYS")
			(pinfunction "1")
			(pintype "passive")
		)
	)
	(footprint "antmicro-footprints:VQFN-18_3x3x1mm_P0.5mm"
		(layer "F.Cu")
		(at 125.526157 56.419672 -90)
		(property "Reference" "U13"
			(at -1.047672 1.828157 270)
			(layer "F.SilkS")
			(effects
				(font
					(size 0.7 0.7)
					(thickness 0.15)
				)
				(justify left bottom)
			)
		)
		(property "Value" "TPS65296"
			(at -2.1 3 270)
			(layer "F.Fab")
			(effects
				(font
					(size 0.7 0.7)
					(thickness 0.15)
				)
				(justify left bottom)
			)
		)
		(property "Description" "DC/DC switching voltage regulator"
			(at 0 0 270)
			(layer "F.Fab")
			(hide yes)
			(effects
				(font
					(size 1.27 1.27)
					(thickness 0.15)
				)
			)
		)
		(property "Author" "Antmicro"
			(at 69.106485 181.945829 0)
			(layer "F.Fab")
			(hide yes)
			(effects
				(font
					(size 1 1)
					(thickness 0.15)
				)
			)
		)
		(property "License" "Apache-2.0"
			(at 69.106485 181.945829 0)
			(layer "F.Fab")
			(hide yes)
			(effects
				(font
					(size 1 1)
					(thickness 0.15)
				)
			)
		)
		(property "MPN" "TPS65296RJER"
			(at 69.106485 181.945829 0)
			(layer "F.Fab")
			(hide yes)
			(effects
				(font
					(size 1 1)
					(thickness 0.15)
				)
			)
		)
		(property "Manufacturer" "Texas Instruments"
			(at 69.106485 181.945829 0)
			(layer "F.Fab")
			(hide yes)
			(effects
				(font
					(size 1 1)
					(thickness 0.15)
				)
			)
		)
		(sheetname "Supply")
		(sheetfile "supply.kicad_sch")
		(attr exclude_from_pos_files exclude_from_bom dnp)
		(fp_line
			(start -1.932 1.929)
			(end -1.621 1.929)
			(stroke
				(width 0.15)
				(type solid)
			)
			(layer "F.SilkS")
		)
		(fp_line
			(start 1.618 1.929)
			(end 1.929 1.929)
			(stroke
				(width 0.15)
				(type solid)
			)
			(layer "F.SilkS")
		)
		(fp_line
			(start 1.929 1.929)
			(end 1.929 1.596)
			(stroke
				(width 0.15)
				(type solid)
			)
			(layer "F.SilkS")
		)
		(fp_line
			(start -1.932 1.596)
			(end -1.932 1.929)
			(stroke
				(width 0.15)
				(type solid)
			)
			(layer "F.SilkS")
		)
		(fp_line
			(start 1.929 -1.597)
			(end 1.929 -1.932)
			(stroke
				(width 0.15)
				(type solid)
			)
			(layer "F.SilkS")
		)
		(fp_line
			(start -1.932 -1.932)
			(end -1.932 -1.597)
			(stroke
				(width 0.15)
				(type solid)
			)
			(layer "F.SilkS")
		)
		(fp_line
			(start -1.621 -1.932)
			(end -1.932 -1.932)
			(stroke
				(width 0.15)
				(type solid)
			)
			(layer "F.SilkS")
		)
		(fp_line
			(start 1.929 -1.932)
			(end 1.618 -1.932)
			(stroke
				(width 0.15)
				(type solid)
			)
			(layer "F.SilkS")
		)
		(fp_circle
			(center -2.246 -1.258)
			(end -2.196 -1.258)
			(stroke
				(width 0.15)
				(type solid)
			)
			(fill no)
			(layer "F.SilkS")
		)
		(fp_poly
			(pts
				(xy -0.352 1.703) (xy -0.551 1.703) (xy -0.551 0.685) (xy -0.352 0.685)
			)
			(stroke
				(width 0.001)
				(type solid)
			)
			(fill yes)
			(layer "F.Paste")
		)
		(fp_poly
			(pts
				(xy 0.548 1.703) (xy 0.349 1.703) (xy 0.349 0.685) (xy 0.548 0.685)
			)
			(stroke
				(width 0.001)
				(type solid)
			)
			(fill yes)
			(layer "F.Paste")
		)
		(fp_poly
			(pts
				(xy 0.099 0.535) (xy -0.1 0.535) (xy -0.1 -0.485) (xy 0.099 -0.485)
			)
			(stroke
				(width 0.001)
				(type solid)
			)
			(fill yes)
			(layer "F.Paste")
		)
		(fp_poly
			(pts
				(xy -0.352 0.484) (xy -0.551 0.484) (xy -0.551 -0.535) (xy -0.352 -0.535)
			)
			(stroke
				(width 0.001)
				(type solid)
			)
			(fill yes)
			(layer "F.Paste")
		)
		(fp_poly
			(pts
				(xy 0.548 0.484) (xy 0.349 0.484) (xy 0.349 -0.535) (xy 0.548 -0.535)
			)
			(stroke
				(width 0.001)
				(type solid)
			)
			(fill yes)
			(layer "F.Paste")
		)
		(fp_poly
			(pts
				(xy 0.099 -0.687) (xy -0.1 -0.687) (xy -0.1 -1.706) (xy 0.099 -1.706)
			)
			(stroke
				(width 0.001)
				(type solid)
			)
			(fill yes)
			(layer "F.Paste")
		)
		(fp_poly
			(pts
				(xy -1.101 1.705) (xy -1.355 1.703) (xy -1.355 1.348) (xy -1.7 1.35) (xy -1.7 1.124) (xy -1.101 1.124)
			)
			(stroke
				(width 0.001)
				(type solid)
			)
			(fill yes)
			(layer "F.Paste")
		)
		(fp_poly
			(pts
				(xy 1.1 1.705) (xy 1.352 1.703) (xy 1.352 1.348) (xy 1.699 1.35) (xy 1.699 1.124) (xy 1.1 1.124)
			)
			(stroke
				(width 0.001)
				(type solid)
			)
			(fill yes)
			(layer "F.Paste")
		)
		(fp_poly
			(pts
				(xy -1.103 -1.706) (xy -1.355 -1.706) (xy -1.355 -1.351) (xy -1.702 -1.351) (xy -1.702 -1.127) (xy -1.103 -1.127)
			)
			(stroke
				(width 0.001)
				(type solid)
			)
			(fill yes)
			(layer "F.Paste")
		)
		(fp_poly
			(pts
				(xy 1.1 -1.706) (xy 1.352 -1.706) (xy 1.352 -1.351) (xy 1.699 -1.351) (xy 1.699 -1.125) (xy 1.1 -1.125)
			)
			(stroke
				(width 0.001)
				(type solid)
			)
			(fill yes)
			(layer "F.Paste")
		)
		(fp_rect
			(start -2 -2)
			(end 2 2)
			(stroke
				(width 0.05)
				(type solid)
			)
			(fill no)
			(layer "F.CrtYd")
		)
		(fp_line
			(start -1.551 1.548)
			(end 1.548 1.548)
			(stroke
				(width 0.15)
				(type solid)
			)
			(layer "F.Fab")
		)
		(fp_line
			(start 1.548 1.548)
			(end 1.548 -1.551)
			(stroke
				(width 0.15)
				(type solid)
			)
			(layer "F.Fab")
		)
		(fp_line
			(start -1.551 -0.802)
			(end -1.551 1.548)
			(stroke
				(width 0.15)
				(type solid)
			)
			(layer "F.Fab")
		)
		(fp_line
			(start -1.551 -0.802)
			(end -0.802 -1.551)
			(stroke
				(width 0.15)
				(type solid)
			)
			(layer "F.Fab")
		)
		(fp_line
			(start 1.548 -1.551)
			(end -0.802 -1.551)
			(stroke
				(width 0.15)
				(type solid)
			)
			(layer "F.Fab")
		)
		(pad "1" smd custom
			(at -1.401 -1.25)
			(size 0.25 0.6)
			(layers "F.Cu" "F.Mask")
			(net 550 "VDD1V1")
			(pinfunction "VLDOIN")
			(pintype "input")
			(options
				(clearance outline)
				(anchor rect)
			)
			(primitives
				(gr_poly
					(pts
						(xy 0.4548 0.3) (xy 0.454997 0.016207) (xy 0.124997 0.016207) (xy 0.125 -0.3) (xy -0.125 -0.3)
						(xy -0.125 0.3)
					)
					(width 0.001)
					(fill yes)
				)
				(gr_poly
					(pts
						(xy 0.4548 0.3) (xy 0.454997 0.016207) (xy 0.124997 0.016207) (xy 0.125 -0.3) (xy -0.125 -0.3)
						(xy -0.125 0.3)
					)
					(width 0.001)
					(fill yes)
				)
			)
		)
		(pad "2" smd rect
			(at -1.401 -0.751)
			(size 0.25 0.6)
			(layers "F.Cu" "F.Mask" "F.Paste")
			(net 627 "/Supply/VDDQ_0V6")
			(pinfunction "VDDQ")
			(pintype "input")
		)
		(pad "3" smd rect
			(at -1.401 -0.25)
			(size 0.25 0.6)
			(layers "F.Cu" "F.Mask" "F.Paste")
			(net 5 "GND")
			(pinfunction "AGND")
			(pintype "input")
		)
		(pad "4" smd rect
			(at -1.401 0.248)
			(size 0.25 0.6)
			(layers "F.Cu" "F.Mask" "F.Paste")
			(net 631 "/Supply/VDDQ_SNS")
			(pinfunction "VDDQSNS")
			(pintype "input")
		)
		(pad "5" smd rect
			(at -1.401 0.749)
			(size 0.25 0.6)
			(layers "F.Cu" "F.Mask" "F.Paste")
			(net 550 "VDD1V1")
			(pinfunction "VDD2SNS")
			(pintype "input")
		)
		(pad "6" smd custom
			(at -1.401 1.249)
			(size 0.25 0.6)
			(layers "F.Cu" "F.Mask" "F.Paste")
			(net 626 "/Supply/VDDQ_REF")
			(pinfunction "VDDQREF")
			(pintype "input")
			(options
				(clearance outline)
				(anchor rect)
			)
			(primitives
				(gr_poly
					(pts
						(xy -0.4548 0.3) (xy -0.454997 0.016207) (xy -0.124997 0.016207) (xy -0.125 -0.3) (xy 0.125 -0.3)
						(xy 0.125 0.3)
					)
					(width 0.001)
					(fill yes)
				)
				(gr_poly
					(pts
						(xy -0.4548 0.3) (xy -0.454997 0.016207) (xy -0.124997 0.016207) (xy -0.125 -0.3) (xy 0.125 -0.3)
						(xy 0.125 0.3)
					)
					(width 0.001)
					(fill yes)
				)
			)
		)
		(pad "7" smd rect
			(at -0.452 0.583 270)
			(size 0.2 2.238)
			(layers "F.Cu" "F.Mask")
			(net 224 "VIN")
			(pinfunction "PVIN")
			(pintype "input")
		)
		(pad "8" smd rect
			(at 0 1.354 270)
			(size 0.2 0.7)
			(layers "F.Cu" "F.Mask" "F.Paste")
			(net 630 "/Supply/LPDDR4_PGOOD")
			(pinfunction "PGOOD")
			(pintype "input")
		)
		(pad "9" smd rect
			(at 0.45 0.583 270)
			(size 0.2 2.238)
			(layers "F.Cu" "F.Mask")
			(net 5 "GND")
			(pinfunction "PGND")
			(pintype "input")
		)
		(pad "10" smd custom
			(at 1.398 1.249 180)
			(size 0.25 0.6)
			(layers "F.Cu" "F.Mask")
			(net 636 "/Supply/0V6_EN")
			(pinfunction "VDDQEN")
			(pintype "input")
			(options
				(clearance outline)
				(anchor rect)
			)
			(primitives
				(gr_poly
					(pts
						(xy 0.4548 0.3) (xy 0.454997 0.016207) (xy 0.124997 0.016207) (xy 0.125 -0.3) (xy -0.125 -0.3)
						(xy -0.125 0.3)
					)
					(width 0.001)
					(fill yes)
				)
				(gr_poly
					(pts
						(xy 0.4548 0.3) (xy 0.454997 0.016207) (xy 0.124997 0.016207) (xy 0.125 -0.3) (xy -0.125 -0.3)
						(xy -0.125 0.3)
					)
					(width 0.001)
					(fill yes)
				)
			)
		)
		(pad "11" smd rect
			(at 1.398 0.749)
			(size 0.25 0.6096)
			(layers "F.Cu" "F.Mask" "F.Paste")
			(net 594 "/Supply/1V8_EN")
			(pinfunction "VDDEN")
			(pintype "input")
		)
		(pad "12" smd rect
			(at 1.398 0.248)
			(size 0.25 0.6096)
			(layers "F.Cu" "F.Mask" "F.Paste")
			(net 551 "/Supply/VDD1V8")
			(pinfunction "VDD1SNS")
			(pintype "input")
		)
		(pad "13" smd rect
			(at 1.398 -0.25)
			(size 0.25 0.6096)
			(layers "F.Cu" "F.Mask" "F.Paste")
			(net 463 "VCC5V0_INT")
			(pinfunction "VCC_5V")
			(pintype "input")
		)
		(pad "14" smd rect
			(at 1.398 -0.751)
			(size 0.25 0.6)
			(layers "F.Cu" "F.Mask" "F.Paste")
			(net 463 "VCC5V0_INT")
			(pinfunction "PIN_VDD1")
			(pintype "input")
		)
		(pad "15" smd custom
			(at 1.398 -1.25 180)
			(size 0.25 0.6)
			(layers "F.Cu" "F.Mask")
			(net 628 "/Supply/VDD1_SW")
			(pinfunction "SW_VDD1")
			(pintype "input")
			(options
				(clearance outline)
				(anchor rect)
			)
			(primitives
				(gr_poly
					(pts
						(xy -0.4548 0.3) (xy -0.454997 0.016207) (xy -0.124997 0.016207) (xy -0.125 -0.3) (xy 0.125 -0.3)
						(xy 0.125 0.3)
					)
					(width 0.001)
					(fill yes)
				)
				(gr_poly
					(pts
						(xy -0.4548 0.3) (xy -0.454997 0.016207) (xy -0.124997 0.016207) (xy -0.125 -0.3) (xy 0.125 -0.3)
						(xy 0.125 0.3)
					)
					(width 0.001)
					(fill yes)
				)
			)
		)
		(pad "16" smd rect
			(at 0.65 -1.401 270)
			(size 0.2 0.6096)
			(layers "F.Cu" "F.Mask" "F.Paste")
			(net 5 "GND")
			(pinfunction "PGND_VDD1")
			(pintype "input")
		)
		(pad "17" smd rect
			(at 0 -0.585 270)
			(size 0.2 2.243)
			(layers "F.Cu" "F.Mask")
			(net 625 "/Supply/VDD2_SW")
			(pinfunction "SW")
			(pintype "input")
		)
		(pad "18" smd rect
			(at -0.652 -1.401 270)
			(size 0.2 0.6096)
			(layers "F.Cu" "F.Mask" "F.Paste")
			(net 629 "/Supply/VDD2_BST")
			(pinfunction "BST")
			(pintype "input")
		)
	)
	(footprint "antmicro-footprints:LED_0603_1608Metric_G"
		(layer "F.Cu")
		(at 115.1492 106.4 180)
		(descr "LED SMD 0603 Green")
		(tags "LED SMD 0603 Green")
		(property "Reference" "PWR6"
			(at 1.4492 -1.4 180)
			(layer "F.SilkS")
			(effects
				(font
					(size 0.7 0.7)
					(thickness 0.15)
				)
				(justify left bottom)
			)
		)
		(property "Value" "LED_G_0603_KP-1608CGCK"
			(at 0 1.6 180)
			(layer "F.Fab")
			(effects
				(font
					(size 0.7 0.7)
					(thickness 0.15)
				)
				(justify left bottom)
			)
		)
		(property "Author" "Antmicro"
			(at 230.2984 212.8 0)
			(layer "F.Fab")
			(hide yes)
			(effects
				(font
					(size 1 1)
					(thickness 0.15)
				)
			)
		)
		(property "License" "Apache-2.0"
			(at 230.2984 212.8 0)
			(layer "F.Fab")
			(hide yes)
			(effects
				(font
					(size 1 1)
					(thickness 0.15)
				)
			)
		)
		(property "MPN" "KP-1608CGCK"
			(at 230.2984 212.8 0)
			(layer "F.Fab")
			(hide yes)
			(effects
				(font
					(size 1 1)
					(thickness 0.15)
				)
			)
		)
		(property "Manufacturer" "Kingbright"
			(at 230.2984 212.8 0)
			(layer "F.Fab")
			(hide yes)
			(effects
				(font
					(size 1 1)
					(thickness 0.15)
				)
			)
		)
		(sheetname "Supply")
		(sheetfile "supply.kicad_sch")
		(attr smd)
		(fp_line
			(start 1.25 0.32)
			(end 1.25 -0.32)
			(stroke
				(width 0.15)
				(type solid)
			)
			(layer "F.SilkS")
		)
		(fp_line
			(start 0.093672 -8e-06)
			(end 0.293672 -8e-06)
			(stroke
				(width 0.1)
				(type solid)
			)
			(layer "F.SilkS")
		)
		(fp_line
			(start 0.093672 -8e-06)
			(end -0.106328 0.199992)
			(stroke
				(width 0.1)
				(type solid)
			)
			(layer "F.SilkS")
		)
		(fp_line
			(start 0.093672 -0.200008)
			(end 0.093672 0.199992)
			(stroke
				(width 0.1)
				(type solid)
			)
			(layer "F.SilkS")
		)
		(fp_line
			(start -0.106328 -8e-06)
			(end -0.29 0)
			(stroke
				(width 0.1)
				(type solid)
			)
			(layer "F.SilkS")
		)
		(fp_line
			(start -0.106328 -0.200008)
			(end 0.093672 -8e-06)
			(stroke
				(width 0.1)
				(type solid)
			)
			(layer "F.SilkS")
		)
		(fp_line
			(start -0.106328 -0.200008)
			(end -0.106328 0.199992)
			(stroke
				(width 0.1)
				(type solid)
			)
			(layer "F.SilkS")
		)
		(fp_line
			(start -0.27 0.351)
			(end 0.27 0.351)
			(stroke
				(width 0.15)
				(type solid)
			)
			(layer "F.SilkS")
		)
		(fp_line
			(start -0.27 -0.35)
			(end 0.27 -0.35)
			(stroke
				(width 0.15)
				(type solid)
			)
			(layer "F.SilkS")
		)
		(fp_rect
			(start 1.26 0.65)
			(end -1.26 -0.65)
			(stroke
				(width 0.05)
				(type solid)
			)
			(fill no)
			(layer "F.CrtYd")
		)
		(fp_line
			(start 0.199 0.202)
			(end 0.199 -0.1)
			(stroke
				(width 0.15)
				(type solid)
			)
			(layer "F.Fab")
		)
		(fp_line
			(start 0.199 0)
			(end 0.597 0)
			(stroke
				(width 0.15)
				(type solid)
			)
			(layer "F.Fab")
		)
		(fp_line
			(start 0.199 -0.2)
			(end 0.199 -0.1)
			(stroke
				(width 0.15)
				(type solid)
			)
			(layer "F.Fab")
		)
		(fp_line
			(start 0.101 0)
			(end -0.201 -0.2)
			(stroke
				(width 0.15)
				(type solid)
			)
			(layer "F.Fab")
		)
		(fp_line
			(start -0.201 0.202)
			(end 0.101 0)
			(stroke
				(width 0.15)
				(type solid)
			)
			(layer "F.Fab")
		)
		(fp_line
			(start -0.201 0)
			(end -0.201 0.202)
			(stroke
				(width 0.15)
				(type solid)
			)
			(layer "F.Fab")
		)
		(fp_line
			(start -0.201 -0.2)
			(end -0.201 0)
			(stroke
				(width 0.15)
				(type solid)
			)
			(layer "F.Fab")
		)
		(fp_line
			(start -0.599 0)
			(end -0.201 0)
			(stroke
				(width 0.15)
				(type solid)
			)
			(layer "F.Fab")
		)
		(fp_rect
			(start -0.848 -0.4)
			(end 0.85 0.402)
			(stroke
				(width 0.15)
				(type solid)
			)
			(fill no)
			(layer "F.Fab")
		)
		(pad "1" smd rect
			(at -0.75 0)
			(size 0.8 0.8)
			(layers "F.Cu" "F.Mask" "F.Paste")
			(net 463 "VCC5V0_INT")
			(pinfunction "1")
			(pintype "passive")
		)
		(pad "2" smd rect
			(at 0.75 0)
			(size 0.8 0.8)
			(layers "F.Cu" "F.Mask" "F.Paste")
			(net 632 "Net-(PWR6-Pad2)")
			(pinfunction "2")
			(pintype "passive")
		)
	)
)
